(kicad_pcb
	(version 20260206)
	(generator "pcbnew")
	(generator_version "10.0")
	(general
		(thickness 1.6)
		(legacy_teardrops no)
	)
	(paper "A4")
	(title_block
		(title "12092022_DA0F0TMDCD0_F0T_Management_Board_D_brd_V3_OCP.brd")
		(comment 1 "Grand Teton / footprints 903-908 of 1440")
	)
	(layers
		(0 "F.Cu" signal "TOP")
		(4 "In1.Cu" signal "GND")
		(6 "In2.Cu" signal "IN1")
		(8 "In3.Cu" signal "GND1")
		(10 "In4.Cu" signal "IN2")
		(12 "In5.Cu" signal "VCC")
		(14 "In6.Cu" signal "VCC1")
		(16 "In7.Cu" signal "IN3")
		(18 "In8.Cu" signal "GND2")
		(20 "In9.Cu" signal "IN4")
		(22 "In10.Cu" signal "GND3")
		(2 "B.Cu" signal "BOTTOM")
		(9 "F.Adhes" user "F.Adhesive")
		(11 "B.Adhes" user "B.Adhesive")
		(13 "F.Paste" user "Package Geometry/Pastemask Top")
		(15 "B.Paste" user "Package Geometry/Pastemask Bottom")
		(5 "F.SilkS" user "Ref Des/Silkscreen Top")
		(7 "B.SilkS" user "Ref Des/Silkscreen Bottom")
		(1 "F.Mask" user "Board Geometry/Soldermask Top")
		(3 "B.Mask" user "Board Geometry/Soldermask Bottom")
		(17 "Dwgs.User" user "User.Drawings")
		(19 "Cmts.User" user "User.Comments")
		(21 "Eco1.User" user "User.Eco1")
		(23 "Eco2.User" user "User.Eco2")
		(25 "Edge.Cuts" user "Board Geometry/Outline")
		(27 "Margin" user)
		(31 "F.CrtYd" user "Package Geometry/Place Bound Top")
		(29 "B.CrtYd" user "Package Geometry/Place Bound Bottom")
		(35 "F.Fab" user "Ref Des/Assembly Top")
		(33 "B.Fab" user "Ref Des/Assembly Bottom")
	)
	(footprint ""
		(layer "B.Cu")
		(at 71.034656 -54.23662)
		(property "Reference" "C3"
			(at 0 0 0)
			(layer "B.SilkS")
			(hide yes)
			(effects
				(font
					(size 1.27 1.27)
				)
				(justify mirror)
			)
		)
		(property "Value" ""
			(at 0 0 0)
			(layer "B.Fab")
			(effects
				(font
					(size 1.27 1.27)
				)
				(justify mirror)
			)
		)
		(duplicate_pad_numbers_are_jumpers no)
		(fp_line
			(start -0.7874 -0.4064)
			(end -0.7874 0.4064)
			(stroke
				(width 0.1524)
				(type default)
			)
			(layer "B.SilkS")
		)
		(fp_line
			(start -0.7874 0.4064)
			(end 0.7874 0.4064)
			(stroke
				(width 0.1524)
				(type default)
			)
			(layer "B.SilkS")
		)
		(fp_line
			(start 0.7874 -0.4064)
			(end -0.7874 -0.4064)
			(stroke
				(width 0.1524)
				(type default)
			)
			(layer "B.SilkS")
		)
		(fp_line
			(start 0.7874 0.4064)
			(end 0.7874 -0.4064)
			(stroke
				(width 0.1524)
				(type default)
			)
			(layer "B.SilkS")
		)
		(fp_line
			(start -0.67945 -0.3048)
			(end -0.67945 0.3048)
			(stroke
				(width 0.1)
				(type default)
			)
			(layer "B.Fab")
		)
		(fp_line
			(start -0.67945 0.3048)
			(end -0.120396 0.3048)
			(stroke
				(width 0.1)
				(type default)
			)
			(layer "B.Fab")
		)
		(fp_line
			(start -0.12065 -0.3048)
			(end -0.67945 -0.3048)
			(stroke
				(width 0.1)
				(type default)
			)
			(layer "B.Fab")
		)
		(fp_line
			(start -0.12065 -0.2794)
			(end -0.12065 -0.3048)
			(stroke
				(width 0.1)
				(type default)
			)
			(layer "B.Fab")
		)
		(fp_line
			(start -0.120396 0.2794)
			(end 0.12065 0.2794)
			(stroke
				(width 0.1)
				(type default)
			)
			(layer "B.Fab")
		)
		(fp_line
			(start -0.120396 0.3048)
			(end -0.120396 0.2794)
			(stroke
				(width 0.1)
				(type default)
			)
			(layer "B.Fab")
		)
		(fp_line
			(start 0.12065 -0.305054)
			(end 0.12065 -0.2794)
			(stroke
				(width 0.1)
				(type default)
			)
			(layer "B.Fab")
		)
		(fp_line
			(start 0.12065 -0.2794)
			(end -0.12065 -0.2794)
			(stroke
				(width 0.1)
				(type default)
			)
			(layer "B.Fab")
		)
		(fp_line
			(start 0.12065 0.2794)
			(end 0.12065 0.3048)
			(stroke
				(width 0.1)
				(type default)
			)
			(layer "B.Fab")
		)
		(fp_line
			(start 0.12065 0.3048)
			(end 0.67945 0.3048)
			(stroke
				(width 0.1)
				(type default)
			)
			(layer "B.Fab")
		)
		(fp_line
			(start 0.67945 -0.305054)
			(end 0.12065 -0.305054)
			(stroke
				(width 0.1)
				(type default)
			)
			(layer "B.Fab")
		)
		(fp_line
			(start 0.67945 0.3048)
			(end 0.67945 -0.305054)
			(stroke
				(width 0.1)
				(type default)
			)
			(layer "B.Fab")
		)
		(pad "1" smd circle
			(at 0.40005 0 180)
			(size 0 0)
			(layers "B.Cu" "B.Mask" "B.Paste")
			(net "P1V2_AUX")
		)
		(pad "2" smd circle
			(at -0.40005 0 180)
			(size 0 0)
			(layers "B.Cu" "B.Mask" "B.Paste")
			(net "GND")
		)
	)
	(footprint ""
		(layer "B.Cu")
		(at 39.930832 -48.915828)
		(property "Reference" "R425"
			(at 0 0 0)
			(layer "B.SilkS")
			(hide yes)
			(effects
				(font
					(size 1.27 1.27)
				)
				(justify mirror)
			)
		)
		(property "Value" ""
			(at 0 0 0)
			(layer "B.Fab")
			(effects
				(font
					(size 1.27 1.27)
				)
				(justify mirror)
			)
		)
		(duplicate_pad_numbers_are_jumpers no)
		(fp_line
			(start -0.7874 -0.4064)
			(end -0.7874 0.4064)
			(stroke
				(width 0.1524)
				(type default)
			)
			(layer "B.SilkS")
		)
		(fp_line
			(start -0.7874 0.4064)
			(end 0.7874 0.4064)
			(stroke
				(width 0.1524)
				(type default)
			)
			(layer "B.SilkS")
		)
		(fp_line
			(start 0.7874 -0.4064)
			(end -0.7874 -0.4064)
			(stroke
				(width 0.1524)
				(type default)
			)
			(layer "B.SilkS")
		)
		(fp_line
			(start 0.7874 0.4064)
			(end 0.7874 -0.4064)
			(stroke
				(width 0.1524)
				(type default)
			)
			(layer "B.SilkS")
		)
		(fp_line
			(start -0.67945 -0.3048)
			(end -0.67945 0.3048)
			(stroke
				(width 0.1)
				(type default)
			)
			(layer "B.Fab")
		)
		(fp_line
			(start -0.67945 0.3048)
			(end -0.120396 0.3048)
			(stroke
				(width 0.1)
				(type default)
			)
			(layer "B.Fab")
		)
		(fp_line
			(start -0.12065 -0.3048)
			(end -0.67945 -0.3048)
			(stroke
				(width 0.1)
				(type default)
			)
			(layer "B.Fab")
		)
		(fp_line
			(start -0.12065 -0.2794)
			(end -0.12065 -0.3048)
			(stroke
				(width 0.1)
				(type default)
			)
			(layer "B.Fab")
		)
		(fp_line
			(start -0.120396 0.2794)
			(end 0.12065 0.2794)
			(stroke
				(width 0.1)
				(type default)
			)
			(layer "B.Fab")
		)
		(fp_line
			(start -0.120396 0.3048)
			(end -0.120396 0.2794)
			(stroke
				(width 0.1)
				(type default)
			)
			(layer "B.Fab")
		)
		(fp_line
			(start 0.12065 -0.305054)
			(end 0.12065 -0.2794)
			(stroke
				(width 0.1)
				(type default)
			)
			(layer "B.Fab")
		)
		(fp_line
			(start 0.12065 -0.2794)
			(end -0.12065 -0.2794)
			(stroke
				(width 0.1)
				(type default)
			)
			(layer "B.Fab")
		)
		(fp_line
			(start 0.12065 0.2794)
			(end 0.12065 0.3048)
			(stroke
				(width 0.1)
				(type default)
			)
			(layer "B.Fab")
		)
		(fp_line
			(start 0.12065 0.3048)
			(end 0.67945 0.3048)
			(stroke
				(width 0.1)
				(type default)
			)
			(layer "B.Fab")
		)
		(fp_line
			(start 0.67945 -0.305054)
			(end 0.12065 -0.305054)
			(stroke
				(width 0.1)
				(type default)
			)
			(layer "B.Fab")
		)
		(fp_line
			(start 0.67945 0.3048)
			(end 0.67945 -0.305054)
			(stroke
				(width 0.1)
				(type default)
			)
			(layer "B.Fab")
		)
		(pad "1" smd circle
			(at 0.40005 0 180)
			(size 0 0)
			(layers "B.Cu" "B.Mask" "B.Paste")
			(net "SMB_BMC_MM14_R_SCL")
		)
		(pad "2" smd circle
			(at -0.40005 0 180)
			(size 0 0)
			(layers "B.Cu" "B.Mask" "B.Paste")
			(net "SMB_BMC_MM14_SCL")
		)
	)
	(footprint ""
		(layer "B.Cu")
		(at 49.39919 -60.207652 -90)
		(property "Reference" "C284"
			(at 0 0 90)
			(layer "B.SilkS")
			(hide yes)
			(effects
				(font
					(size 1.27 1.27)
				)
				(justify mirror)
			)
		)
		(property "Value" ""
			(at 0 0 90)
			(layer "B.Fab")
			(effects
				(font
					(size 1.27 1.27)
				)
				(justify mirror)
			)
		)
		(duplicate_pad_numbers_are_jumpers no)
		(fp_line
			(start -0.7874 0.4064)
			(end 0.7874 0.4064)
			(stroke
				(width 0.1524)
				(type default)
			)
			(layer "B.SilkS")
		)
		(fp_line
			(start 0.7874 0.4064)
			(end 0.7874 -0.4064)
			(stroke
				(width 0.1524)
				(type default)
			)
			(layer "B.SilkS")
		)
		(fp_line
			(start -0.7874 -0.4064)
			(end -0.7874 0.4064)
			(stroke
				(width 0.1524)
				(type default)
			)
			(layer "B.SilkS")
		)
		(fp_line
			(start 0.7874 -0.4064)
			(end -0.7874 -0.4064)
			(stroke
				(width 0.1524)
				(type default)
			)
			(layer "B.SilkS")
		)
		(fp_line
			(start -0.67945 0.3048)
			(end -0.120396 0.3048)
			(stroke
				(width 0.1)
				(type default)
			)
			(layer "B.Fab")
		)
		(fp_line
			(start -0.120396 0.3048)
			(end -0.120396 0.2794)
			(stroke
				(width 0.1)
				(type default)
			)
			(layer "B.Fab")
		)
		(fp_line
			(start 0.12065 0.3048)
			(end 0.67945 0.3048)
			(stroke
				(width 0.1)
				(type default)
			)
			(layer "B.Fab")
		)
		(fp_line
			(start 0.67945 0.3048)
			(end 0.67945 -0.305054)
			(stroke
				(width 0.1)
				(type default)
			)
			(layer "B.Fab")
		)
		(fp_line
			(start -0.120396 0.2794)
			(end 0.12065 0.2794)
			(stroke
				(width 0.1)
				(type default)
			)
			(layer "B.Fab")
		)
		(fp_line
			(start 0.12065 0.2794)
			(end 0.12065 0.3048)
			(stroke
				(width 0.1)
				(type default)
			)
			(layer "B.Fab")
		)
		(fp_line
			(start -0.12065 -0.2794)
			(end -0.12065 -0.3048)
			(stroke
				(width 0.1)
				(type default)
			)
			(layer "B.Fab")
		)
		(fp_line
			(start 0.12065 -0.2794)
			(end -0.12065 -0.2794)
			(stroke
				(width 0.1)
				(type default)
			)
			(layer "B.Fab")
		)
		(fp_line
			(start -0.67945 -0.3048)
			(end -0.67945 0.3048)
			(stroke
				(width 0.1)
				(type default)
			)
			(layer "B.Fab")
		)
		(fp_line
			(start -0.12065 -0.3048)
			(end -0.67945 -0.3048)
			(stroke
				(width 0.1)
				(type default)
			)
			(layer "B.Fab")
		)
		(fp_line
			(start 0.12065 -0.305054)
			(end 0.12065 -0.2794)
			(stroke
				(width 0.1)
				(type default)
			)
			(layer "B.Fab")
		)
		(fp_line
			(start 0.67945 -0.305054)
			(end 0.12065 -0.305054)
			(stroke
				(width 0.1)
				(type default)
			)
			(layer "B.Fab")
		)
		(pad "1" smd circle
			(at 0.40005 0 90)
			(size 0 0)
			(layers "B.Cu" "B.Mask" "B.Paste")
			(net "ADCVREFEXT0")
		)
		(pad "2" smd circle
			(at -0.40005 0 90)
			(size 0 0)
			(layers "B.Cu" "B.Mask" "B.Paste")
			(net "GND")
		)
	)
	(footprint ""
		(layer "B.Cu")
		(at 71.374 -41.402 -90)
		(property "Reference" "C40"
			(at 0 0 90)
			(layer "B.SilkS")
			(hide yes)
			(effects
				(font
					(size 1.27 1.27)
				)
				(justify mirror)
			)
		)
		(property "Value" ""
			(at 0 0 90)
			(layer "B.Fab")
			(effects
				(font
					(size 1.27 1.27)
				)
				(justify mirror)
			)
		)
		(duplicate_pad_numbers_are_jumpers no)
		(fp_line
			(start -1.2954 0.5842)
			(end 1.2954 0.5842)
			(stroke
				(width 0.1524)
				(type default)
			)
			(layer "B.SilkS")
		)
		(fp_line
			(start 1.2954 0.5842)
			(end 1.2954 -0.5842)
			(stroke
				(width 0.1524)
				(type default)
			)
			(layer "B.SilkS")
		)
		(fp_line
			(start -1.2954 -0.5842)
			(end -1.2954 0.5842)
			(stroke
				(width 0.1524)
				(type default)
			)
			(layer "B.SilkS")
		)
		(fp_line
			(start 0 -0.5842)
			(end 0 0.5842)
			(stroke
				(width 0.1524)
				(type default)
			)
			(layer "B.SilkS")
		)
		(fp_line
			(start 1.2954 -0.5842)
			(end -1.2954 -0.5842)
			(stroke
				(width 0.1524)
				(type default)
			)
			(layer "B.SilkS")
		)
		(fp_line
			(start -0.8636 0.4572)
			(end 0.8636 0.4572)
			(stroke
				(width 0.1)
				(type default)
			)
			(layer "B.Fab")
		)
		(fp_line
			(start 0.8636 0.4572)
			(end 0.8636 0.4064)
			(stroke
				(width 0.1)
				(type default)
			)
			(layer "B.Fab")
		)
		(fp_line
			(start -1.1938 0.4064)
			(end -0.8636 0.4064)
			(stroke
				(width 0.1)
				(type default)
			)
			(layer "B.Fab")
		)
		(fp_line
			(start -0.8636 0.4064)
			(end -0.8636 0.4572)
			(stroke
				(width 0.1)
				(type default)
			)
			(layer "B.Fab")
		)
		(fp_line
			(start 0.8636 0.4064)
			(end 1.1938 0.4064)
			(stroke
				(width 0.1)
				(type default)
			)
			(layer "B.Fab")
		)
		(fp_line
			(start 1.1938 0.4064)
			(end 1.1938 -0.4064)
			(stroke
				(width 0.1)
				(type default)
			)
			(layer "B.Fab")
		)
		(fp_line
			(start -1.1938 -0.4064)
			(end -1.1938 0.4064)
			(stroke
				(width 0.1)
				(type default)
			)
			(layer "B.Fab")
		)
		(fp_line
			(start -0.8636 -0.4064)
			(end -1.1938 -0.4064)
			(stroke
				(width 0.1)
				(type default)
			)
			(layer "B.Fab")
		)
		(fp_line
			(start 0.8636 -0.4064)
			(end 0.8636 -0.4572)
			(stroke
				(width 0.1)
				(type default)
			)
			(layer "B.Fab")
		)
		(fp_line
			(start 1.1938 -0.4064)
			(end 0.8636 -0.4064)
			(stroke
				(width 0.1)
				(type default)
			)
			(layer "B.Fab")
		)
		(fp_line
			(start -0.8636 -0.4572)
			(end -0.8636 -0.4064)
			(stroke
				(width 0.1)
				(type default)
			)
			(layer "B.Fab")
		)
		(fp_line
			(start 0.8636 -0.4572)
			(end -0.8636 -0.4572)
			(stroke
				(width 0.1)
				(type default)
			)
			(layer "B.Fab")
		)
		(pad "1" smd rect
			(at 0.7366 0 180)
			(size 0.7112 0.8128)
			(layers "B.Cu" "B.Mask" "B.Paste")
			(net "P1V8_BMC_USB2AV18")
		)
		(pad "2" smd rect
			(at -0.7366 0 180)
			(size 0.7112 0.8128)
			(layers "B.Cu" "B.Mask" "B.Paste")
			(net "GND")
		)
	)
	(footprint ""
		(layer "B.Cu")
		(at 22.987 -18.669 -90)
		(property "Reference" "C197"
			(at 0 0 90)
			(layer "B.SilkS")
			(hide yes)
			(effects
				(font
					(size 1.27 1.27)
				)
				(justify mirror)
			)
		)
		(property "Value" ""
			(at 0 0 90)
			(layer "B.Fab")
			(effects
				(font
					(size 1.27 1.27)
				)
				(justify mirror)
			)
		)
		(duplicate_pad_numbers_are_jumpers no)
		(fp_line
			(start -0.7874 0.4064)
			(end 0.7874 0.4064)
			(stroke
				(width 0.1524)
				(type default)
			)
			(layer "B.SilkS")
		)
		(fp_line
			(start 0.7874 0.4064)
			(end 0.7874 -0.4064)
			(stroke
				(width 0.1524)
				(type default)
			)
			(layer "B.SilkS")
		)
		(fp_line
			(start -0.7874 -0.4064)
			(end -0.7874 0.4064)
			(stroke
				(width 0.1524)
				(type default)
			)
			(layer "B.SilkS")
		)
		(fp_line
			(start 0.7874 -0.4064)
			(end -0.7874 -0.4064)
			(stroke
				(width 0.1524)
				(type default)
			)
			(layer "B.SilkS")
		)
		(fp_line
			(start -0.67945 0.3048)
			(end -0.120396 0.3048)
			(stroke
				(width 0.1)
				(type default)
			)
			(layer "B.Fab")
		)
		(fp_line
			(start -0.120396 0.3048)
			(end -0.120396 0.2794)
			(stroke
				(width 0.1)
				(type default)
			)
			(layer "B.Fab")
		)
		(fp_line
			(start 0.12065 0.3048)
			(end 0.67945 0.3048)
			(stroke
				(width 0.1)
				(type default)
			)
			(layer "B.Fab")
		)
		(fp_line
			(start 0.67945 0.3048)
			(end 0.67945 -0.305054)
			(stroke
				(width 0.1)
				(type default)
			)
			(layer "B.Fab")
		)
		(fp_line
			(start -0.120396 0.2794)
			(end 0.12065 0.2794)
			(stroke
				(width 0.1)
				(type default)
			)
			(layer "B.Fab")
		)
		(fp_line
			(start 0.12065 0.2794)
			(end 0.12065 0.3048)
			(stroke
				(width 0.1)
				(type default)
			)
			(layer "B.Fab")
		)
		(fp_line
			(start -0.12065 -0.2794)
			(end -0.12065 -0.3048)
			(stroke
				(width 0.1)
				(type default)
			)
			(layer "B.Fab")
		)
		(fp_line
			(start 0.12065 -0.2794)
			(end -0.12065 -0.2794)
			(stroke
				(width 0.1)
				(type default)
			)
			(layer "B.Fab")
		)
		(fp_line
			(start -0.67945 -0.3048)
			(end -0.67945 0.3048)
			(stroke
				(width 0.1)
				(type default)
			)
			(layer "B.Fab")
		)
		(fp_line
			(start -0.12065 -0.3048)
			(end -0.67945 -0.3048)
			(stroke
				(width 0.1)
				(type default)
			)
			(layer "B.Fab")
		)
		(fp_line
			(start 0.12065 -0.305054)
			(end 0.12065 -0.2794)
			(stroke
				(width 0.1)
				(type default)
			)
			(layer "B.Fab")
		)
		(fp_line
			(start 0.67945 -0.305054)
			(end 0.12065 -0.305054)
			(stroke
				(width 0.1)
				(type default)
			)
			(layer "B.Fab")
		)
		(pad "1" smd circle
			(at 0.40005 0 90)
			(size 0 0)
			(layers "B.Cu" "B.Mask" "B.Paste")
			(net "HDD_LED_P5V_AUX")
		)
		(pad "2" smd circle
			(at -0.40005 0 90)
			(size 0 0)
			(layers "B.Cu" "B.Mask" "B.Paste")
			(net "GND")
		)
	)
	(footprint ""
		(layer "B.Cu")
		(at 50.8 -28.829 -90)
		(property "Reference" "R879"
			(at 0 0 90)
			(layer "B.SilkS")
			(hide yes)
			(effects
				(font
					(size 1.27 1.27)
				)
				(justify mirror)
			)
		)
		(property "Value" ""
			(at 0 0 90)
			(layer "B.Fab")
			(effects
				(font
					(size 1.27 1.27)
				)
				(justify mirror)
			)
		)
		(duplicate_pad_numbers_are_jumpers no)
		(fp_line
			(start -0.7874 0.4064)
			(end 0.7874 0.4064)
			(stroke
				(width 0.1524)
				(type default)
			)
			(layer "B.SilkS")
		)
		(fp_line
			(start 0.7874 0.4064)
			(end 0.7874 -0.4064)
			(stroke
				(width 0.1524)
				(type default)
			)
			(layer "B.SilkS")
		)
		(fp_line
			(start -0.7874 -0.4064)
			(end -0.7874 0.4064)
			(stroke
				(width 0.1524)
				(type default)
			)
			(layer "B.SilkS")
		)
		(fp_line
			(start 0.7874 -0.4064)
			(end -0.7874 -0.4064)
			(stroke
				(width 0.1524)
				(type default)
			)
			(layer "B.SilkS")
		)
		(fp_line
			(start -0.67945 0.3048)
			(end -0.120396 0.3048)
			(stroke
				(width 0.1)
				(type default)
			)
			(layer "B.Fab")
		)
		(fp_line
			(start -0.120396 0.3048)
			(end -0.120396 0.2794)
			(stroke
				(width 0.1)
				(type default)
			)
			(layer "B.Fab")
		)
		(fp_line
			(start 0.12065 0.3048)
			(end 0.67945 0.3048)
			(stroke
				(width 0.1)
				(type default)
			)
			(layer "B.Fab")
		)
		(fp_line
			(start 0.67945 0.3048)
			(end 0.67945 -0.305054)
			(stroke
				(width 0.1)
				(type default)
			)
			(layer "B.Fab")
		)
		(fp_line
			(start -0.120396 0.2794)
			(end 0.12065 0.2794)
			(stroke
				(width 0.1)
				(type default)
			)
			(layer "B.Fab")
		)
		(fp_line
			(start 0.12065 0.2794)
			(end 0.12065 0.3048)
			(stroke
				(width 0.1)
				(type default)
			)
			(layer "B.Fab")
		)
		(fp_line
			(start -0.12065 -0.2794)
			(end -0.12065 -0.3048)
			(stroke
				(width 0.1)
				(type default)
			)
			(layer "B.Fab")
		)
		(fp_line
			(start 0.12065 -0.2794)
			(end -0.12065 -0.2794)
			(stroke
				(width 0.1)
				(type default)
			)
			(layer "B.Fab")
		)
		(fp_line
			(start -0.67945 -0.3048)
			(end -0.67945 0.3048)
			(stroke
				(width 0.1)
				(type default)
			)
			(layer "B.Fab")
		)
		(fp_line
			(start -0.12065 -0.3048)
			(end -0.67945 -0.3048)
			(stroke
				(width 0.1)
				(type default)
			)
			(layer "B.Fab")
		)
		(fp_line
			(start 0.12065 -0.305054)
			(end 0.12065 -0.2794)
			(stroke
				(width 0.1)
				(type default)
			)
			(layer "B.Fab")
		)
		(fp_line
			(start 0.67945 -0.305054)
			(end 0.12065 -0.305054)
			(stroke
				(width 0.1)
				(type default)
			)
			(layer "B.Fab")
		)
		(pad "1" smd circle
			(at 0.40005 0 90)
			(size 0 0)
			(layers "B.Cu" "B.Mask" "B.Paste")
			(net "SMB_BMC_MM16_R5_SCL")
		)
		(pad "2" smd circle
			(at -0.40005 0 90)
			(size 0 0)
			(layers "B.Cu" "B.Mask" "B.Paste")
			(net "SMB_BMC_MM16_SCL")
		)
	)
)
